(kicad_pcb
	(version 20260206)
	(generator "pcbnew")
	(generator_version "10.0")
	(general
		(thickness 1.6)
		(legacy_teardrops no)
	)
	(paper "A4")
	(title_block
		(title "01162023_DA0F0TEBIF0_F0T_Expander_BD_F_brd_V02_OCP.brd")
		(comment 1 "Grand Teton / footprints 6694-6700 of 9728")
	)
	(layers
		(0 "F.Cu" signal "TOP")
		(4 "In1.Cu" signal "GND")
		(6 "In2.Cu" signal "VCC")
		(8 "In3.Cu" signal "VCC1")
		(10 "In4.Cu" signal "GND1")
		(12 "In5.Cu" signal "IN1")
		(14 "In6.Cu" signal "GND2")
		(16 "In7.Cu" signal "IN2")
		(18 "In8.Cu" signal "GND3")
		(20 "In9.Cu" signal "IN3")
		(22 "In10.Cu" signal "GND4")
		(24 "In11.Cu" signal "IN4")
		(26 "In12.Cu" signal "GND5")
		(28 "In13.Cu" signal "IN5")
		(30 "In14.Cu" signal "GND6")
		(32 "In15.Cu" signal "IN6")
		(34 "In16.Cu" signal "GND7")
		(2 "B.Cu" signal "BOTTOM")
		(9 "F.Adhes" user "F.Adhesive")
		(11 "B.Adhes" user "B.Adhesive")
		(13 "F.Paste" user "Package Geometry/Pastemask Top")
		(15 "B.Paste" user "Package Geometry/Pastemask Bottom")
		(5 "F.SilkS" user "Ref Des/Silkscreen Top")
		(7 "B.SilkS" user "Ref Des/Silkscreen Bottom")
		(1 "F.Mask" user "Board Geometry/Soldermask Top")
		(3 "B.Mask" user "Board Geometry/Soldermask Bottom")
		(17 "Dwgs.User" user "User.Drawings")
		(19 "Cmts.User" user "User.Comments")
		(21 "Eco1.User" user "User.Eco1")
		(23 "Eco2.User" user "User.Eco2")
		(25 "Edge.Cuts" user "Board Geometry/Outline")
		(27 "Margin" user)
		(31 "F.CrtYd" user "Package Geometry/Place Bound Top")
		(29 "B.CrtYd" user "Package Geometry/Place Bound Bottom")
		(35 "F.Fab" user "Ref Des/Assembly Top")
		(33 "B.Fab" user "Ref Des/Assembly Bottom")
	)
	(footprint ""
		(layer "F.Cu")
		(at 165.212014 -210.09991)
		(property "Reference" "ME3"
			(at 0 0 0)
			(layer "F.SilkS")
			(hide yes)
			(effects
				(font
					(size 1.27 1.27)
				)
			)
		)
		(property "Value" ""
			(at 0 0 0)
			(layer "F.Fab")
			(effects
				(font
					(size 1.27 1.27)
				)
			)
		)
		(duplicate_pad_numbers_are_jumpers no)
	)
	(footprint ""
		(layer "F.Cu")
		(at 325.130668 -229.526592 -90)
		(property "Reference" "R3006"
			(at 0 0 270)
			(layer "F.SilkS")
			(hide yes)
			(effects
				(font
					(size 1.27 1.27)
				)
			)
		)
		(property "Value" ""
			(at 0 0 270)
			(layer "F.Fab")
			(effects
				(font
					(size 1.27 1.27)
				)
			)
		)
		(duplicate_pad_numbers_are_jumpers no)
		(fp_line
			(start -0.7874 0.4064)
			(end -0.7874 -0.4064)
			(stroke
				(width 0.1524)
				(type default)
			)
			(layer "F.SilkS")
		)
		(fp_line
			(start 0.7874 0.4064)
			(end -0.7874 0.4064)
			(stroke
				(width 0.1524)
				(type default)
			)
			(layer "F.SilkS")
		)
		(fp_line
			(start -0.7874 -0.4064)
			(end 0.7874 -0.4064)
			(stroke
				(width 0.1524)
				(type default)
			)
			(layer "F.SilkS")
		)
		(fp_line
			(start 0.7874 -0.4064)
			(end 0.7874 0.4064)
			(stroke
				(width 0.1524)
				(type default)
			)
			(layer "F.SilkS")
		)
		(fp_line
			(start -0.67945 0.3048)
			(end -0.67945 -0.305054)
			(stroke
				(width 0.1)
				(type default)
			)
			(layer "F.Fab")
		)
		(fp_line
			(start -0.12065 0.3048)
			(end -0.67945 0.3048)
			(stroke
				(width 0.1)
				(type default)
			)
			(layer "F.Fab")
		)
		(fp_line
			(start 0.120396 0.3048)
			(end 0.120396 0.2794)
			(stroke
				(width 0.1)
				(type default)
			)
			(layer "F.Fab")
		)
		(fp_line
			(start 0.67945 0.3048)
			(end 0.120396 0.3048)
			(stroke
				(width 0.1)
				(type default)
			)
			(layer "F.Fab")
		)
		(fp_line
			(start -0.12065 0.2794)
			(end -0.12065 0.3048)
			(stroke
				(width 0.1)
				(type default)
			)
			(layer "F.Fab")
		)
		(fp_line
			(start 0.120396 0.2794)
			(end -0.12065 0.2794)
			(stroke
				(width 0.1)
				(type default)
			)
			(layer "F.Fab")
		)
		(fp_line
			(start -0.12065 -0.2794)
			(end 0.12065 -0.2794)
			(stroke
				(width 0.1)
				(type default)
			)
			(layer "F.Fab")
		)
		(fp_line
			(start 0.12065 -0.2794)
			(end 0.12065 -0.3048)
			(stroke
				(width 0.1)
				(type default)
			)
			(layer "F.Fab")
		)
		(fp_line
			(start 0.12065 -0.3048)
			(end 0.67945 -0.3048)
			(stroke
				(width 0.1)
				(type default)
			)
			(layer "F.Fab")
		)
		(fp_line
			(start 0.67945 -0.3048)
			(end 0.67945 0.3048)
			(stroke
				(width 0.1)
				(type default)
			)
			(layer "F.Fab")
		)
		(fp_line
			(start -0.67945 -0.305054)
			(end -0.12065 -0.305054)
			(stroke
				(width 0.1)
				(type default)
			)
			(layer "F.Fab")
		)
		(fp_line
			(start -0.12065 -0.305054)
			(end -0.12065 -0.2794)
			(stroke
				(width 0.1)
				(type default)
			)
			(layer "F.Fab")
		)
		(pad "1" smd circle
			(at -0.40005 0 270)
			(size 0 0)
			(layers "F.Cu" "F.Mask" "F.Paste")
			(net "P3V3_LED")
		)
		(pad "2" smd circle
			(at 0.40005 0 270)
			(size 0 0)
			(layers "F.Cu" "F.Mask" "F.Paste")
			(net "FPGA_HEARTBEAT")
		)
	)
	(footprint ""
		(layer "F.Cu")
		(at 244.81282 -288.017204)
		(property "Reference" "PC256"
			(at 0 0 0)
			(layer "F.SilkS")
			(hide yes)
			(effects
				(font
					(size 1.27 1.27)
				)
			)
		)
		(property "Value" ""
			(at 0 0 0)
			(layer "F.Fab")
			(effects
				(font
					(size 1.27 1.27)
				)
			)
		)
		(duplicate_pad_numbers_are_jumpers no)
		(fp_line
			(start -0.7874 -0.4064)
			(end 0.7874 -0.4064)
			(stroke
				(width 0.1524)
				(type default)
			)
			(layer "F.SilkS")
		)
		(fp_line
			(start -0.7874 0.4064)
			(end -0.7874 -0.4064)
			(stroke
				(width 0.1524)
				(type default)
			)
			(layer "F.SilkS")
		)
		(fp_line
			(start 0.7874 -0.4064)
			(end 0.7874 0.4064)
			(stroke
				(width 0.1524)
				(type default)
			)
			(layer "F.SilkS")
		)
		(fp_line
			(start 0.7874 0.4064)
			(end -0.7874 0.4064)
			(stroke
				(width 0.1524)
				(type default)
			)
			(layer "F.SilkS")
		)
		(fp_line
			(start -0.67945 -0.305054)
			(end -0.12065 -0.305054)
			(stroke
				(width 0.1)
				(type default)
			)
			(layer "F.Fab")
		)
		(fp_line
			(start -0.67945 0.3048)
			(end -0.67945 -0.305054)
			(stroke
				(width 0.1)
				(type default)
			)
			(layer "F.Fab")
		)
		(fp_line
			(start -0.12065 -0.305054)
			(end -0.12065 -0.2794)
			(stroke
				(width 0.1)
				(type default)
			)
			(layer "F.Fab")
		)
		(fp_line
			(start -0.12065 -0.2794)
			(end 0.12065 -0.2794)
			(stroke
				(width 0.1)
				(type default)
			)
			(layer "F.Fab")
		)
		(fp_line
			(start -0.12065 0.2794)
			(end -0.12065 0.3048)
			(stroke
				(width 0.1)
				(type default)
			)
			(layer "F.Fab")
		)
		(fp_line
			(start -0.12065 0.3048)
			(end -0.67945 0.3048)
			(stroke
				(width 0.1)
				(type default)
			)
			(layer "F.Fab")
		)
		(fp_line
			(start 0.120396 0.2794)
			(end -0.12065 0.2794)
			(stroke
				(width 0.1)
				(type default)
			)
			(layer "F.Fab")
		)
		(fp_line
			(start 0.120396 0.3048)
			(end 0.120396 0.2794)
			(stroke
				(width 0.1)
				(type default)
			)
			(layer "F.Fab")
		)
		(fp_line
			(start 0.12065 -0.3048)
			(end 0.67945 -0.3048)
			(stroke
				(width 0.1)
				(type default)
			)
			(layer "F.Fab")
		)
		(fp_line
			(start 0.12065 -0.2794)
			(end 0.12065 -0.3048)
			(stroke
				(width 0.1)
				(type default)
			)
			(layer "F.Fab")
		)
		(fp_line
			(start 0.67945 -0.3048)
			(end 0.67945 0.3048)
			(stroke
				(width 0.1)
				(type default)
			)
			(layer "F.Fab")
		)
		(fp_line
			(start 0.67945 0.3048)
			(end 0.120396 0.3048)
			(stroke
				(width 0.1)
				(type default)
			)
			(layer "F.Fab")
		)
		(pad "1" smd circle
			(at -0.40005 0)
			(size 0 0)
			(layers "F.Cu" "F.Mask" "F.Paste")
			(net "P1V25_PEX2_R")
		)
		(pad "2" smd circle
			(at 0.40005 0)
			(size 0 0)
			(layers "F.Cu" "F.Mask" "F.Paste")
			(net "GND")
		)
	)
	(footprint ""
		(layer "F.Cu")
		(at 378.738384 -250.070874 -90)
		(property "Reference" "R1405"
			(at 0 0 270)
			(layer "F.SilkS")
			(hide yes)
			(effects
				(font
					(size 1.27 1.27)
				)
			)
		)
		(property "Value" ""
			(at 0 0 270)
			(layer "F.Fab")
			(effects
				(font
					(size 1.27 1.27)
				)
			)
		)
		(duplicate_pad_numbers_are_jumpers no)
		(fp_line
			(start -0.7874 0.4064)
			(end -0.7874 -0.4064)
			(stroke
				(width 0.1524)
				(type default)
			)
			(layer "F.SilkS")
		)
		(fp_line
			(start 0.7874 0.4064)
			(end -0.7874 0.4064)
			(stroke
				(width 0.1524)
				(type default)
			)
			(layer "F.SilkS")
		)
		(fp_line
			(start -0.7874 -0.4064)
			(end 0.7874 -0.4064)
			(stroke
				(width 0.1524)
				(type default)
			)
			(layer "F.SilkS")
		)
		(fp_line
			(start 0.7874 -0.4064)
			(end 0.7874 0.4064)
			(stroke
				(width 0.1524)
				(type default)
			)
			(layer "F.SilkS")
		)
		(fp_line
			(start -0.67945 0.3048)
			(end -0.67945 -0.305054)
			(stroke
				(width 0.1)
				(type default)
			)
			(layer "F.Fab")
		)
		(fp_line
			(start -0.12065 0.3048)
			(end -0.67945 0.3048)
			(stroke
				(width 0.1)
				(type default)
			)
			(layer "F.Fab")
		)
		(fp_line
			(start 0.120396 0.3048)
			(end 0.120396 0.2794)
			(stroke
				(width 0.1)
				(type default)
			)
			(layer "F.Fab")
		)
		(fp_line
			(start 0.67945 0.3048)
			(end 0.120396 0.3048)
			(stroke
				(width 0.1)
				(type default)
			)
			(layer "F.Fab")
		)
		(fp_line
			(start -0.12065 0.2794)
			(end -0.12065 0.3048)
			(stroke
				(width 0.1)
				(type default)
			)
			(layer "F.Fab")
		)
		(fp_line
			(start 0.120396 0.2794)
			(end -0.12065 0.2794)
			(stroke
				(width 0.1)
				(type default)
			)
			(layer "F.Fab")
		)
		(fp_line
			(start -0.12065 -0.2794)
			(end 0.12065 -0.2794)
			(stroke
				(width 0.1)
				(type default)
			)
			(layer "F.Fab")
		)
		(fp_line
			(start 0.12065 -0.2794)
			(end 0.12065 -0.3048)
			(stroke
				(width 0.1)
				(type default)
			)
			(layer "F.Fab")
		)
		(fp_line
			(start 0.12065 -0.3048)
			(end 0.67945 -0.3048)
			(stroke
				(width 0.1)
				(type default)
			)
			(layer "F.Fab")
		)
		(fp_line
			(start 0.67945 -0.3048)
			(end 0.67945 0.3048)
			(stroke
				(width 0.1)
				(type default)
			)
			(layer "F.Fab")
		)
		(fp_line
			(start -0.67945 -0.305054)
			(end -0.12065 -0.305054)
			(stroke
				(width 0.1)
				(type default)
			)
			(layer "F.Fab")
		)
		(fp_line
			(start -0.12065 -0.305054)
			(end -0.12065 -0.2794)
			(stroke
				(width 0.1)
				(type default)
			)
			(layer "F.Fab")
		)
		(pad "1" smd circle
			(at -0.40005 0 270)
			(size 0 0)
			(layers "F.Cu" "F.Mask" "F.Paste")
			(net "PEX3_MODE_SEL0")
		)
		(pad "2" smd circle
			(at 0.40005 0 270)
			(size 0 0)
			(layers "F.Cu" "F.Mask" "F.Paste")
			(net "P1V8_PEX")
		)
	)
	(footprint ""
		(layer "F.Cu")
		(at 149.303486 -390.398254 -90)
		(property "Reference" "R1841"
			(at 0 0 270)
			(layer "F.SilkS")
			(hide yes)
			(effects
				(font
					(size 1.27 1.27)
				)
			)
		)
		(property "Value" ""
			(at 0 0 270)
			(layer "F.Fab")
			(effects
				(font
					(size 1.27 1.27)
				)
			)
		)
		(duplicate_pad_numbers_are_jumpers no)
		(fp_line
			(start -0.7874 0.4064)
			(end -0.7874 -0.4064)
			(stroke
				(width 0.1524)
				(type default)
			)
			(layer "F.SilkS")
		)
		(fp_line
			(start 0.7874 0.4064)
			(end -0.7874 0.4064)
			(stroke
				(width 0.1524)
				(type default)
			)
			(layer "F.SilkS")
		)
		(fp_line
			(start -0.7874 -0.4064)
			(end 0.7874 -0.4064)
			(stroke
				(width 0.1524)
				(type default)
			)
			(layer "F.SilkS")
		)
		(fp_line
			(start 0.7874 -0.4064)
			(end 0.7874 0.4064)
			(stroke
				(width 0.1524)
				(type default)
			)
			(layer "F.SilkS")
		)
		(fp_line
			(start -0.67945 0.3048)
			(end -0.67945 -0.305054)
			(stroke
				(width 0.1)
				(type default)
			)
			(layer "F.Fab")
		)
		(fp_line
			(start -0.12065 0.3048)
			(end -0.67945 0.3048)
			(stroke
				(width 0.1)
				(type default)
			)
			(layer "F.Fab")
		)
		(fp_line
			(start 0.120396 0.3048)
			(end 0.120396 0.2794)
			(stroke
				(width 0.1)
				(type default)
			)
			(layer "F.Fab")
		)
		(fp_line
			(start 0.67945 0.3048)
			(end 0.120396 0.3048)
			(stroke
				(width 0.1)
				(type default)
			)
			(layer "F.Fab")
		)
		(fp_line
			(start -0.12065 0.2794)
			(end -0.12065 0.3048)
			(stroke
				(width 0.1)
				(type default)
			)
			(layer "F.Fab")
		)
		(fp_line
			(start 0.120396 0.2794)
			(end -0.12065 0.2794)
			(stroke
				(width 0.1)
				(type default)
			)
			(layer "F.Fab")
		)
		(fp_line
			(start -0.12065 -0.2794)
			(end 0.12065 -0.2794)
			(stroke
				(width 0.1)
				(type default)
			)
			(layer "F.Fab")
		)
		(fp_line
			(start 0.12065 -0.2794)
			(end 0.12065 -0.3048)
			(stroke
				(width 0.1)
				(type default)
			)
			(layer "F.Fab")
		)
		(fp_line
			(start 0.12065 -0.3048)
			(end 0.67945 -0.3048)
			(stroke
				(width 0.1)
				(type default)
			)
			(layer "F.Fab")
		)
		(fp_line
			(start 0.67945 -0.3048)
			(end 0.67945 0.3048)
			(stroke
				(width 0.1)
				(type default)
			)
			(layer "F.Fab")
		)
		(fp_line
			(start -0.67945 -0.305054)
			(end -0.12065 -0.305054)
			(stroke
				(width 0.1)
				(type default)
			)
			(layer "F.Fab")
		)
		(fp_line
			(start -0.12065 -0.305054)
			(end -0.12065 -0.2794)
			(stroke
				(width 0.1)
				(type default)
			)
			(layer "F.Fab")
		)
		(pad "1" smd circle
			(at -0.40005 0 270)
			(size 0 0)
			(layers "F.Cu" "F.Mask" "F.Paste")
			(net "GPU_BASE_HMC_READY_R")
		)
		(pad "2" smd circle
			(at 0.40005 0 270)
			(size 0 0)
			(layers "F.Cu" "F.Mask" "F.Paste")
			(net "GPU_BASE_HMC_READY")
		)
	)
	(footprint ""
		(layer "F.Cu")
		(at 252.85954 -61.612526)
		(property "Reference" "PD113"
			(at -3.7084 -2.733548 0)
			(unlocked yes)
			(layer "F.SilkS")
			(effects
				(font
					(size 0.7874 0.5842)
					(thickness 0.1524)
				)
				(justify left)
			)
		)
		(property "Value" ""
			(at 0 0 0)
			(layer "F.Fab")
			(effects
				(font
					(size 1.27 1.27)
				)
			)
		)
		(duplicate_pad_numbers_are_jumpers no)
		(fp_line
			(start -3.656584 -1.970024)
			(end -3.656584 1.970024)
			(stroke
				(width 0.1524)
				(type default)
			)
			(layer "F.SilkS")
		)
		(fp_line
			(start -3.656584 1.970024)
			(end 4.240784 1.970024)
			(stroke
				(width 0.1524)
				(type default)
			)
			(layer "F.SilkS")
		)
		(fp_line
			(start 4.240784 -1.970024)
			(end -3.656584 -1.970024)
			(stroke
				(width 0.1524)
				(type default)
			)
			(layer "F.SilkS")
		)
		(fp_line
			(start 4.240784 1.970024)
			(end 4.240784 -1.970024)
			(stroke
				(width 0.1524)
				(type default)
			)
			(layer "F.SilkS")
		)
		(fp_poly
			(pts
				(xy 3.580384 1.970024) (xy 3.580384 -1.970024) (xy 4.240784 -1.970024) (xy 4.240784 1.970024)
			)
			(stroke
				(width 0)
				(type default)
			)
			(fill yes)
			(layer "F.SilkS")
		)
		(fp_line
			(start -2.3749 -1.970024)
			(end -2.3749 1.970024)
			(stroke
				(width 0.1)
				(type default)
			)
			(layer "F.Fab")
		)
		(fp_line
			(start -2.3749 1.970024)
			(end 2.3749 1.970024)
			(stroke
				(width 0.1)
				(type default)
			)
			(layer "F.Fab")
		)
		(fp_line
			(start 2.3749 -1.970024)
			(end -2.3749 -1.970024)
			(stroke
				(width 0.1)
				(type default)
			)
			(layer "F.Fab")
		)
		(fp_line
			(start 2.3749 1.970024)
			(end 2.3749 -1.970024)
			(stroke
				(width 0.1)
				(type default)
			)
			(layer "F.Fab")
		)
		(fp_text user "+"
			(at -4.9784 -0.23495 0)
			(unlocked yes)
			(layer "F.Fab")
			(effects
				(font
					(size 1.905 1.4224)
					(thickness 0.1524)
				)
				(justify left)
			)
		)
		(fp_text user "-"
			(at 4.1656 -0.23495 0)
			(unlocked yes)
			(layer "F.Fab")
			(effects
				(font
					(size 1.905 1.4224)
					(thickness 0.1524)
				)
				(justify left)
			)
		)
		(pad "A" smd rect
			(at -2.450084 0)
			(size 2.159 2.2606)
			(layers "F.Cu" "F.Mask" "F.Paste")
			(net "GND")
		)
		(pad "C" smd rect
			(at 2.450084 0)
			(size 2.159 2.2606)
			(layers "F.Cu" "F.Mask" "F.Paste")
			(net "P12V_AUX")
		)
	)
	(footprint ""
		(layer "F.Cu")
		(at 81.639664 -87.349076 -90)
		(property "Reference" "R96"
			(at 0 0 270)
			(layer "F.SilkS")
			(hide yes)
			(effects
				(font
					(size 1.27 1.27)
				)
			)
		)
		(property "Value" ""
			(at 0 0 270)
			(layer "F.Fab")
			(effects
				(font
					(size 1.27 1.27)
				)
			)
		)
		(duplicate_pad_numbers_are_jumpers no)
		(fp_line
			(start -0.7874 0.4064)
			(end -0.7874 -0.4064)
			(stroke
				(width 0.1524)
				(type default)
			)
			(layer "F.SilkS")
		)
		(fp_line
			(start 0.7874 0.4064)
			(end -0.7874 0.4064)
			(stroke
				(width 0.1524)
				(type default)
			)
			(layer "F.SilkS")
		)
		(fp_line
			(start -0.7874 -0.4064)
			(end 0.7874 -0.4064)
			(stroke
				(width 0.1524)
				(type default)
			)
			(layer "F.SilkS")
		)
		(fp_line
			(start 0.7874 -0.4064)
			(end 0.7874 0.4064)
			(stroke
				(width 0.1524)
				(type default)
			)
			(layer "F.SilkS")
		)
		(fp_line
			(start -0.67945 0.3048)
			(end -0.67945 -0.305054)
			(stroke
				(width 0.1)
				(type default)
			)
			(layer "F.Fab")
		)
		(fp_line
			(start -0.12065 0.3048)
			(end -0.67945 0.3048)
			(stroke
				(width 0.1)
				(type default)
			)
			(layer "F.Fab")
		)
		(fp_line
			(start 0.120396 0.3048)
			(end 0.120396 0.2794)
			(stroke
				(width 0.1)
				(type default)
			)
			(layer "F.Fab")
		)
		(fp_line
			(start 0.67945 0.3048)
			(end 0.120396 0.3048)
			(stroke
				(width 0.1)
				(type default)
			)
			(layer "F.Fab")
		)
		(fp_line
			(start -0.12065 0.2794)
			(end -0.12065 0.3048)
			(stroke
				(width 0.1)
				(type default)
			)
			(layer "F.Fab")
		)
		(fp_line
			(start 0.120396 0.2794)
			(end -0.12065 0.2794)
			(stroke
				(width 0.1)
				(type default)
			)
			(layer "F.Fab")
		)
		(fp_line
			(start -0.12065 -0.2794)
			(end 0.12065 -0.2794)
			(stroke
				(width 0.1)
				(type default)
			)
			(layer "F.Fab")
		)
		(fp_line
			(start 0.12065 -0.2794)
			(end 0.12065 -0.3048)
			(stroke
				(width 0.1)
				(type default)
			)
			(layer "F.Fab")
		)
		(fp_line
			(start 0.12065 -0.3048)
			(end 0.67945 -0.3048)
			(stroke
				(width 0.1)
				(type default)
			)
			(layer "F.Fab")
		)
		(fp_line
			(start 0.67945 -0.3048)
			(end 0.67945 0.3048)
			(stroke
				(width 0.1)
				(type default)
			)
			(layer "F.Fab")
		)
		(fp_line
			(start -0.67945 -0.305054)
			(end -0.12065 -0.305054)
			(stroke
				(width 0.1)
				(type default)
			)
			(layer "F.Fab")
		)
		(fp_line
			(start -0.12065 -0.305054)
			(end -0.12065 -0.2794)
			(stroke
				(width 0.1)
				(type default)
			)
			(layer "F.Fab")
		)
		(pad "1" smd circle
			(at -0.40005 0 270)
			(size 0 0)
			(layers "F.Cu" "F.Mask" "F.Paste")
			(net "RST_NIC1_PERST0_R_N")
		)
		(pad "2" smd circle
			(at 0.40005 0 270)
			(size 0 0)
			(layers "F.Cu" "F.Mask" "F.Paste")
			(net "RST_HP_NIC1_BUF_N")
		)
	)
)
